# T6G (Grand Teton) — schematic netlist excerpt (pin names and nets, part order shuffled) for the footprints in the layout excerpt that follows; sources: Cadence DE-HDL packaged netlist, KiCad conversion of 04192023_DAF0TMB3IC0_F0TG_MB_C_brd_V02_OCP.brd

R3475  Q_RES  100K 1% CHIP  pkg 0402LF  page 126 : A = P3V3_AUX ; B = GPU_PRSNT_N_ISO
C2112  Q_CAP  22UF 4V 20% X6S  pkg C0402  page 74 : A = PVDDIO_P1 ; B = GND

(kicad_pcb
	(version 20260206)
	(generator "pcbnew")
	(generator_version "10.0")
	(general
		(thickness 1.6)
		(legacy_teardrops no)
	)
	(paper "A4")
	(title_block
		(title "04192023_DAF0TMB3IC0_F0TG_MB_C_brd_V02_OCP.brd")
		(comment 1 "Grand Teton / footprints 8025-8026 of 8354")
	)
	(layers
		(0 "F.Cu" signal "TOP")
		(4 "In1.Cu" signal "GND")
		(6 "In2.Cu" signal "IN1")
		(8 "In3.Cu" signal "GND1")
		(10 "In4.Cu" signal "IN2")
		(12 "In5.Cu" signal "GND2")
		(14 "In6.Cu" signal "IN3")
		(16 "In7.Cu" signal "GND3")
		(18 "In8.Cu" signal "VCC")
		(20 "In9.Cu" signal "VCC1")
		(22 "In10.Cu" signal "GND4")
		(24 "In11.Cu" signal "IN4")
		(26 "In12.Cu" signal "GND5")
		(28 "In13.Cu" signal "IN5")
		(30 "In14.Cu" signal "GND6")
		(32 "In15.Cu" signal "IN6")
		(34 "In16.Cu" signal "GND7")
		(2 "B.Cu" signal "BOTTOM")
		(9 "F.Adhes" user "F.Adhesive")
		(11 "B.Adhes" user "B.Adhesive")
		(13 "F.Paste" user "Package Geometry/Pastemask Top")
		(15 "B.Paste" user "Package Geometry/Pastemask Bottom")
		(5 "F.SilkS" user "Ref Des/Silkscreen Top")
		(7 "B.SilkS" user "Ref Des/Silkscreen Bottom")
		(1 "F.Mask" user "Board Geometry/Soldermask Top")
		(3 "B.Mask" user "Board Geometry/Soldermask Bottom")
		(17 "Dwgs.User" user "User.Drawings")
		(19 "Cmts.User" user "User.Comments")
		(21 "Eco1.User" user "User.Eco1")
		(23 "Eco2.User" user "User.Eco2")
		(25 "Edge.Cuts" user "Board Geometry/Outline")
		(27 "Margin" user)
		(31 "F.CrtYd" user "Package Geometry/Place Bound Top")
		(29 "B.CrtYd" user "Package Geometry/Place Bound Bottom")
		(35 "F.Fab" user "Ref Des/Assembly Top")
		(33 "B.Fab" user "Ref Des/Assembly Bottom")
	)
	(footprint ""
		(layer "B.Cu")
		(at 52.782978 -428.06493 -90)
		(property "Reference" "R3475"
			(at 0 0 90)
			(layer "B.SilkS")
			(hide yes)
			(effects
				(font
					(size 1.27 1.27)
				)
				(justify mirror)
			)
		)
		(property "Value" ""
			(at 0 0 90)
			(layer "B.Fab")
			(effects
				(font
					(size 1.27 1.27)
				)
				(justify mirror)
			)
		)
		(duplicate_pad_numbers_are_jumpers no)
		(fp_line
			(start -0.7874 0.4064)
			(end 0.7874 0.4064)
			(stroke
				(width 0.1524)
				(type default)
			)
			(layer "B.SilkS")
		)
		(fp_line
			(start 0.7874 0.4064)
			(end 0.7874 -0.4064)
			(stroke
				(width 0.1524)
				(type default)
			)
			(layer "B.SilkS")
		)
		(fp_line
			(start -0.7874 -0.4064)
			(end -0.7874 0.4064)
			(stroke
				(width 0.1524)
				(type default)
			)
			(layer "B.SilkS")
		)
		(fp_line
			(start 0.7874 -0.4064)
			(end -0.7874 -0.4064)
			(stroke
				(width 0.1524)
				(type default)
			)
			(layer "B.SilkS")
		)
		(fp_line
			(start -0.67945 0.3048)
			(end -0.120396 0.3048)
			(stroke
				(width 0.1)
				(type default)
			)
			(layer "B.Fab")
		)
		(fp_line
			(start -0.120396 0.3048)
			(end -0.120396 0.2794)
			(stroke
				(width 0.1)
				(type default)
			)
			(layer "B.Fab")
		)
		(fp_line
			(start 0.12065 0.3048)
			(end 0.67945 0.3048)
			(stroke
				(width 0.1)
				(type default)
			)
			(layer "B.Fab")
		)
		(fp_line
			(start 0.67945 0.3048)
			(end 0.67945 -0.305054)
			(stroke
				(width 0.1)
				(type default)
			)
			(layer "B.Fab")
		)
		(fp_line
			(start -0.120396 0.2794)
			(end 0.12065 0.2794)
			(stroke
				(width 0.1)
				(type default)
			)
			(layer "B.Fab")
		)
		(fp_line
			(start 0.12065 0.2794)
			(end 0.12065 0.3048)
			(stroke
				(width 0.1)
				(type default)
			)
			(layer "B.Fab")
		)
		(fp_line
			(start -0.12065 -0.2794)
			(end -0.12065 -0.3048)
			(stroke
				(width 0.1)
				(type default)
			)
			(layer "B.Fab")
		)
		(fp_line
			(start 0.12065 -0.2794)
			(end -0.12065 -0.2794)
			(stroke
				(width 0.1)
				(type default)
			)
			(layer "B.Fab")
		)
		(fp_line
			(start -0.67945 -0.3048)
			(end -0.67945 0.3048)
			(stroke
				(width 0.1)
				(type default)
			)
			(layer "B.Fab")
		)
		(fp_line
			(start -0.12065 -0.3048)
			(end -0.67945 -0.3048)
			(stroke
				(width 0.1)
				(type default)
			)
			(layer "B.Fab")
		)
		(fp_line
			(start 0.12065 -0.305054)
			(end 0.12065 -0.2794)
			(stroke
				(width 0.1)
				(type default)
			)
			(layer "B.Fab")
		)
		(fp_line
			(start 0.67945 -0.305054)
			(end 0.12065 -0.305054)
			(stroke
				(width 0.1)
				(type default)
			)
			(layer "B.Fab")
		)
		(pad "1" smd circle
			(at 0.40005 0 90)
			(size 0 0)
			(layers "B.Cu" "B.Mask" "B.Paste")
			(net "P3V3_AUX")
		)
		(pad "2" smd circle
			(at -0.40005 0 90)
			(size 0 0)
			(layers "B.Cu" "B.Mask" "B.Paste")
			(net "GPU_PRSNT_N_ISO")
		)
	)
	(footprint ""
		(layer "B.Cu")
		(at 100.478844 -257.930396 180)
		(property "Reference" "C2112"
			(at 0 0 0)
			(layer "B.SilkS")
			(hide yes)
			(effects
				(font
					(size 1.27 1.27)
				)
				(justify mirror)
			)
		)
		(property "Value" ""
			(at 0 0 0)
			(layer "B.Fab")
			(effects
				(font
					(size 1.27 1.27)
				)
				(justify mirror)
			)
		)
		(duplicate_pad_numbers_are_jumpers no)
		(fp_line
			(start 0.7874 0.4064)
			(end 0.7874 -0.4064)
			(stroke
				(width 0.1524)
				(type default)
			)
			(layer "B.SilkS")
		)
		(fp_line
			(start 0.7874 -0.4064)
			(end -0.7874 -0.4064)
			(stroke
				(width 0.1524)
				(type default)
			)
			(layer "B.SilkS")
		)
		(fp_line
			(start -0.7874 0.4064)
			(end 0.7874 0.4064)
			(stroke
				(width 0.1524)
				(type default)
			)
			(layer "B.SilkS")
		)
		(fp_line
			(start -0.7874 -0.4064)
			(end -0.7874 0.4064)
			(stroke
				(width 0.1524)
				(type default)
			)
			(layer "B.SilkS")
		)
		(fp_line
			(start 0.67945 0.3048)
			(end 0.67945 -0.305054)
			(stroke
				(width 0.1)
				(type default)
			)
			(layer "B.Fab")
		)
		(fp_line
			(start 0.67945 -0.305054)
			(end 0.12065 -0.305054)
			(stroke
				(width 0.1)
				(type default)
			)
			(layer "B.Fab")
		)
		(fp_line
			(start 0.12065 0.3048)
			(end 0.67945 0.3048)
			(stroke
				(width 0.1)
				(type default)
			)
			(layer "B.Fab")
		)
		(fp_line
			(start 0.12065 0.2794)
			(end 0.12065 0.3048)
			(stroke
				(width 0.1)
				(type default)
			)
			(layer "B.Fab")
		)
		(fp_line
			(start 0.12065 -0.2794)
			(end -0.12065 -0.2794)
			(stroke
				(width 0.1)
				(type default)
			)
			(layer "B.Fab")
		)
		(fp_line
			(start 0.12065 -0.305054)
			(end 0.12065 -0.2794)
			(stroke
				(width 0.1)
				(type default)
			)
			(layer "B.Fab")
		)
		(fp_line
			(start -0.120396 0.3048)
			(end -0.120396 0.2794)
			(stroke
				(width 0.1)
				(type default)
			)
			(layer "B.Fab")
		)
		(fp_line
			(start -0.120396 0.2794)
			(end 0.12065 0.2794)
			(stroke
				(width 0.1)
				(type default)
			)
			(layer "B.Fab")
		)
		(fp_line
			(start -0.12065 -0.2794)
			(end -0.12065 -0.3048)
			(stroke
				(width 0.1)
				(type default)
			)
			(layer "B.Fab")
		)
		(fp_line
			(start -0.12065 -0.3048)
			(end -0.67945 -0.3048)
			(stroke
				(width 0.1)
				(type default)
			)
			(layer "B.Fab")
		)
		(fp_line
			(start -0.67945 0.3048)
			(end -0.120396 0.3048)
			(stroke
				(width 0.1)
				(type default)
			)
			(layer "B.Fab")
		)
		(fp_line
			(start -0.67945 -0.3048)
			(end -0.67945 0.3048)
			(stroke
				(width 0.1)
				(type default)
			)
			(layer "B.Fab")
		)
		(pad "1" smd circle
			(at 0.40005 0)
			(size 0 0)
			(layers "B.Cu" "B.Mask" "B.Paste")
			(net "PVDDIO_P1")
		)
		(pad "2" smd circle
			(at -0.40005 0)
			(size 0 0)
			(layers "B.Cu" "B.Mask" "B.Paste")
			(net "GND")
		)
	)
)
